# T6G (Grand Teton) — schematic netlist excerpt (pin names and nets, part order shuffled) for the footprints in the layout excerpt that follows; sources: Cadence DE-HDL packaged netlist, KiCad conversion of 04192023_DAF0TMB3IC0_F0TG_MB_C_brd_V02_OCP.brd

R3390  Q_RES  49.9 1% CHIP  pkg 0402LF  page 128 : A = GPU_FPGA_BOOT_EN_BUF_R ; B = GPU_FPGA_BOOT_EN_BUF
R758  Q_RES  4.7K 5% EMPTY  pkg 0201LF  page 331 : A = P1V8_CPU1_RT_1D ; B = RST_RT_CPU1_P1_RESET_R_N

(kicad_pcb
	(version 20260206)
	(generator "pcbnew")
	(generator_version "10.0")
	(general
		(thickness 1.6)
		(legacy_teardrops no)
	)
	(paper "A4")
	(title_block
		(title "04192023_DAF0TMB3IC0_F0TG_MB_C_brd_V02_OCP.brd")
		(comment 1 "Grand Teton / footprints 3442-3443 of 8354")
	)
	(layers
		(0 "F.Cu" signal "TOP")
		(4 "In1.Cu" signal "GND")
		(6 "In2.Cu" signal "IN1")
		(8 "In3.Cu" signal "GND1")
		(10 "In4.Cu" signal "IN2")
		(12 "In5.Cu" signal "GND2")
		(14 "In6.Cu" signal "IN3")
		(16 "In7.Cu" signal "GND3")
		(18 "In8.Cu" signal "VCC")
		(20 "In9.Cu" signal "VCC1")
		(22 "In10.Cu" signal "GND4")
		(24 "In11.Cu" signal "IN4")
		(26 "In12.Cu" signal "GND5")
		(28 "In13.Cu" signal "IN5")
		(30 "In14.Cu" signal "GND6")
		(32 "In15.Cu" signal "IN6")
		(34 "In16.Cu" signal "GND7")
		(2 "B.Cu" signal "BOTTOM")
		(9 "F.Adhes" user "F.Adhesive")
		(11 "B.Adhes" user "B.Adhesive")
		(13 "F.Paste" user "Package Geometry/Pastemask Top")
		(15 "B.Paste" user "Package Geometry/Pastemask Bottom")
		(5 "F.SilkS" user "Ref Des/Silkscreen Top")
		(7 "B.SilkS" user "Ref Des/Silkscreen Bottom")
		(1 "F.Mask" user "Board Geometry/Soldermask Top")
		(3 "B.Mask" user "Board Geometry/Soldermask Bottom")
		(17 "Dwgs.User" user "User.Drawings")
		(19 "Cmts.User" user "User.Comments")
		(21 "Eco1.User" user "User.Eco1")
		(23 "Eco2.User" user "User.Eco2")
		(25 "Edge.Cuts" user "Board Geometry/Outline")
		(27 "Margin" user)
		(31 "F.CrtYd" user "Package Geometry/Place Bound Top")
		(29 "B.CrtYd" user "Package Geometry/Place Bound Bottom")
		(35 "F.Fab" user "Ref Des/Assembly Top")
		(33 "B.Fab" user "Ref Des/Assembly Bottom")
	)
	(footprint ""
		(layer "F.Cu")
		(at 120.396 -423.672 180)
		(property "Reference" "R3390"
			(at 0 0 180)
			(layer "F.SilkS")
			(hide yes)
			(effects
				(font
					(size 1.27 1.27)
				)
			)
		)
		(property "Value" ""
			(at 0 0 180)
			(layer "F.Fab")
			(effects
				(font
					(size 1.27 1.27)
				)
			)
		)
		(duplicate_pad_numbers_are_jumpers no)
		(fp_line
			(start 0.7874 0.4064)
			(end -0.7874 0.4064)
			(stroke
				(width 0.1524)
				(type default)
			)
			(layer "F.SilkS")
		)
		(fp_line
			(start 0.7874 -0.4064)
			(end 0.7874 0.4064)
			(stroke
				(width 0.1524)
				(type default)
			)
			(layer "F.SilkS")
		)
		(fp_line
			(start -0.7874 0.4064)
			(end -0.7874 -0.4064)
			(stroke
				(width 0.1524)
				(type default)
			)
			(layer "F.SilkS")
		)
		(fp_line
			(start -0.7874 -0.4064)
			(end 0.7874 -0.4064)
			(stroke
				(width 0.1524)
				(type default)
			)
			(layer "F.SilkS")
		)
		(fp_line
			(start 0.67945 0.3048)
			(end 0.120396 0.3048)
			(stroke
				(width 0.1)
				(type default)
			)
			(layer "F.Fab")
		)
		(fp_line
			(start 0.67945 -0.3048)
			(end 0.67945 0.3048)
			(stroke
				(width 0.1)
				(type default)
			)
			(layer "F.Fab")
		)
		(fp_line
			(start 0.12065 -0.2794)
			(end 0.12065 -0.3048)
			(stroke
				(width 0.1)
				(type default)
			)
			(layer "F.Fab")
		)
		(fp_line
			(start 0.12065 -0.3048)
			(end 0.67945 -0.3048)
			(stroke
				(width 0.1)
				(type default)
			)
			(layer "F.Fab")
		)
		(fp_line
			(start 0.120396 0.3048)
			(end 0.120396 0.2794)
			(stroke
				(width 0.1)
				(type default)
			)
			(layer "F.Fab")
		)
		(fp_line
			(start 0.120396 0.2794)
			(end -0.12065 0.2794)
			(stroke
				(width 0.1)
				(type default)
			)
			(layer "F.Fab")
		)
		(fp_line
			(start -0.12065 0.3048)
			(end -0.67945 0.3048)
			(stroke
				(width 0.1)
				(type default)
			)
			(layer "F.Fab")
		)
		(fp_line
			(start -0.12065 0.2794)
			(end -0.12065 0.3048)
			(stroke
				(width 0.1)
				(type default)
			)
			(layer "F.Fab")
		)
		(fp_line
			(start -0.12065 -0.2794)
			(end 0.12065 -0.2794)
			(stroke
				(width 0.1)
				(type default)
			)
			(layer "F.Fab")
		)
		(fp_line
			(start -0.12065 -0.305054)
			(end -0.12065 -0.2794)
			(stroke
				(width 0.1)
				(type default)
			)
			(layer "F.Fab")
		)
		(fp_line
			(start -0.67945 0.3048)
			(end -0.67945 -0.305054)
			(stroke
				(width 0.1)
				(type default)
			)
			(layer "F.Fab")
		)
		(fp_line
			(start -0.67945 -0.305054)
			(end -0.12065 -0.305054)
			(stroke
				(width 0.1)
				(type default)
			)
			(layer "F.Fab")
		)
		(pad "1" smd circle
			(at -0.40005 0 180)
			(size 0 0)
			(layers "F.Cu" "F.Mask" "F.Paste")
			(net "GPU_FPGA_BOOT_EN_BUF_R")
		)
		(pad "2" smd circle
			(at 0.40005 0 180)
			(size 0 0)
			(layers "F.Cu" "F.Mask" "F.Paste")
			(net "GPU_FPGA_BOOT_EN_BUF")
		)
	)
	(footprint ""
		(layer "F.Cu")
		(at 77.215746 -395.436852 -90)
		(property "Reference" "R758"
			(at 0 0 270)
			(layer "F.SilkS")
			(hide yes)
			(effects
				(font
					(size 1.27 1.27)
				)
			)
		)
		(property "Value" ""
			(at 0 0 270)
			(layer "F.Fab")
			(effects
				(font
					(size 1.27 1.27)
				)
			)
		)
		(duplicate_pad_numbers_are_jumpers no)
		(fp_line
			(start -0.32512 0.175006)
			(end -0.32512 -0.175006)
			(stroke
				(width 0.1)
				(type default)
			)
			(layer "F.Fab")
		)
		(fp_line
			(start 0.32512 0.175006)
			(end -0.32512 0.175006)
			(stroke
				(width 0.1)
				(type default)
			)
			(layer "F.Fab")
		)
		(fp_line
			(start -0.32512 -0.175006)
			(end 0.32512 -0.175006)
			(stroke
				(width 0.1)
				(type default)
			)
			(layer "F.Fab")
		)
		(fp_line
			(start 0.32512 -0.175006)
			(end 0.32512 0.175006)
			(stroke
				(width 0.1)
				(type default)
			)
			(layer "F.Fab")
		)
		(pad "1" smd rect
			(at -0.2667 0 270)
			(size 0.3048 0.381)
			(layers "F.Cu" "F.Mask" "F.Paste")
			(net "P1V8_CPU1_RT_1D")
		)
		(pad "2" smd rect
			(at 0.2667 0 90)
			(size 0.3048 0.381)
			(layers "F.Cu" "F.Mask" "F.Paste")
			(net "RST_RT_CPU1_P1_RESET_R_N")
		)
	)
)
